(kicad_pcb
	(version 20260206)
	(generator "pcbnew")
	(generator_version "10.0")
	(general
		(thickness 1.6)
		(legacy_teardrops no)
	)
	(paper "A4")
	(title_block
		(title "03242023_DA0F0TMBIJ0_F0T_Motherboard_J_brd_V01_OCP.brd")
		(comment 1 "Grand Teton / footprints 5016-5021 of 6105")
	)
	(layers
		(0 "F.Cu" signal "TOP")
		(4 "In1.Cu" signal "GND")
		(6 "In2.Cu" signal "IN1")
		(8 "In3.Cu" signal "GND1")
		(10 "In4.Cu" signal "IN2")
		(12 "In5.Cu" signal "GND2")
		(14 "In6.Cu" signal "IN3")
		(16 "In7.Cu" signal "GND3")
		(18 "In8.Cu" signal "VCC")
		(20 "In9.Cu" signal "VCC1")
		(22 "In10.Cu" signal "GND4")
		(24 "In11.Cu" signal "IN4")
		(26 "In12.Cu" signal "GND5")
		(28 "In13.Cu" signal "IN5")
		(30 "In14.Cu" signal "GND6")
		(32 "In15.Cu" signal "IN6")
		(34 "In16.Cu" signal "GND7")
		(2 "B.Cu" signal "BOTTOM")
		(9 "F.Adhes" user "F.Adhesive")
		(11 "B.Adhes" user "B.Adhesive")
		(13 "F.Paste" user "Package Geometry/Pastemask Top")
		(15 "B.Paste" user "Package Geometry/Pastemask Bottom")
		(5 "F.SilkS" user "Ref Des/Silkscreen Top")
		(7 "B.SilkS" user "Ref Des/Silkscreen Bottom")
		(1 "F.Mask" user "Board Geometry/Soldermask Top")
		(3 "B.Mask" user "Board Geometry/Soldermask Bottom")
		(17 "Dwgs.User" user "User.Drawings")
		(19 "Cmts.User" user "User.Comments")
		(21 "Eco1.User" user "User.Eco1")
		(23 "Eco2.User" user "User.Eco2")
		(25 "Edge.Cuts" user "Board Geometry/Outline")
		(27 "Margin" user)
		(31 "F.CrtYd" user "Package Geometry/Place Bound Top")
		(29 "B.CrtYd" user "Package Geometry/Place Bound Bottom")
		(35 "F.Fab" user "Ref Des/Assembly Top")
		(33 "B.Fab" user "Ref Des/Assembly Bottom")
	)
	(footprint ""
		(layer "B.Cu")
		(at 409.284932 -170.821858 180)
		(property "Reference" "PC1575"
			(at 0 0 0)
			(layer "B.SilkS")
			(hide yes)
			(effects
				(font
					(size 1.27 1.27)
				)
				(justify mirror)
			)
		)
		(property "Value" ""
			(at 0 0 0)
			(layer "B.Fab")
			(effects
				(font
					(size 1.27 1.27)
				)
				(justify mirror)
			)
		)
		(duplicate_pad_numbers_are_jumpers no)
		(fp_line
			(start 4.84378 -2.150618)
			(end 4.842256 2.163064)
			(stroke
				(width 0.1524)
				(type default)
			)
			(layer "B.SilkS")
		)
		(fp_line
			(start 4.84378 -2.150618)
			(end 4.53898 -2.150618)
			(stroke
				(width 0.1524)
				(type default)
			)
			(layer "B.SilkS")
		)
		(fp_line
			(start 4.83108 2.150364)
			(end 4.447794 2.149348)
			(stroke
				(width 0.1524)
				(type default)
			)
			(layer "B.SilkS")
		)
		(fp_line
			(start 4.69138 -2.150618)
			(end 4.692396 2.161032)
			(stroke
				(width 0.1524)
				(type default)
			)
			(layer "B.SilkS")
		)
		(fp_line
			(start 4.53898 2.15011)
			(end 4.53898 -2.15011)
			(stroke
				(width 0.1524)
				(type default)
			)
			(layer "B.SilkS")
		)
		(fp_line
			(start 4.53898 -2.15011)
			(end -4.53898 -2.15011)
			(stroke
				(width 0.1524)
				(type default)
			)
			(layer "B.SilkS")
		)
		(fp_line
			(start 4.53898 -2.150618)
			(end 4.539742 2.152142)
			(stroke
				(width 0.1524)
				(type default)
			)
			(layer "B.SilkS")
		)
		(fp_line
			(start -4.53898 2.15011)
			(end 4.53898 2.15011)
			(stroke
				(width 0.1524)
				(type default)
			)
			(layer "B.SilkS")
		)
		(fp_line
			(start -4.53898 -2.15011)
			(end -4.53898 2.15011)
			(stroke
				(width 0.1524)
				(type default)
			)
			(layer "B.SilkS")
		)
		(fp_line
			(start 3.64998 2.15011)
			(end 3.64998 -2.15011)
			(stroke
				(width 0.1)
				(type default)
			)
			(layer "B.Fab")
		)
		(fp_line
			(start 3.64998 -2.15011)
			(end -3.64998 -2.15011)
			(stroke
				(width 0.1)
				(type default)
			)
			(layer "B.Fab")
		)
		(fp_line
			(start -3.64998 2.15011)
			(end 3.64998 2.15011)
			(stroke
				(width 0.1)
				(type default)
			)
			(layer "B.Fab")
		)
		(fp_line
			(start -3.64998 -2.15011)
			(end -3.64998 2.15011)
			(stroke
				(width 0.1)
				(type default)
			)
			(layer "B.Fab")
		)
		(fp_text user "+"
			(at 6.214872 -0.337058 180)
			(unlocked yes)
			(layer "B.SilkS")
			(effects
				(font
					(size 1.905 1.4224)
					(thickness 0.1524)
				)
				(justify left mirror)
			)
		)
		(fp_text user "-"
			(at -5.702808 0.98806 180)
			(unlocked yes)
			(layer "B.SilkS")
			(effects
				(font
					(size 1.905 1.4224)
					(thickness 0.1524)
				)
				(justify left mirror)
			)
		)
		(fp_text user "+"
			(at 6.214872 -0.337058 180)
			(unlocked yes)
			(layer "B.Fab")
			(effects
				(font
					(size 1.905 1.4224)
					(thickness 0.1524)
				)
				(justify left mirror)
			)
		)
		(fp_text user "-"
			(at -4.313174 -0.094488 180)
			(unlocked yes)
			(layer "B.Fab")
			(effects
				(font
					(size 1.905 1.4224)
					(thickness 0.1524)
				)
				(justify left mirror)
			)
		)
		(pad "1" smd rect
			(at 3.199892 0)
			(size 2.413 2.8194)
			(layers "B.Cu" "B.Mask" "B.Paste")
			(net "PVCCINFAON_CPU0")
		)
		(pad "2" smd rect
			(at -3.199892 0)
			(size 2.413 2.8194)
			(layers "B.Cu" "B.Mask" "B.Paste")
			(net "GND")
		)
	)
	(footprint ""
		(layer "B.Cu")
		(at 12.003532 -99.925632 180)
		(property "Reference" "C2033"
			(at 0 0 0)
			(layer "B.SilkS")
			(hide yes)
			(effects
				(font
					(size 1.27 1.27)
				)
				(justify mirror)
			)
		)
		(property "Value" ""
			(at 0 0 0)
			(layer "B.Fab")
			(effects
				(font
					(size 1.27 1.27)
				)
				(justify mirror)
			)
		)
		(duplicate_pad_numbers_are_jumpers no)
		(fp_line
			(start 0.7874 0.4064)
			(end 0.7874 -0.4064)
			(stroke
				(width 0.1524)
				(type default)
			)
			(layer "B.SilkS")
		)
		(fp_line
			(start 0.7874 -0.4064)
			(end -0.7874 -0.4064)
			(stroke
				(width 0.1524)
				(type default)
			)
			(layer "B.SilkS")
		)
		(fp_line
			(start -0.7874 0.4064)
			(end 0.7874 0.4064)
			(stroke
				(width 0.1524)
				(type default)
			)
			(layer "B.SilkS")
		)
		(fp_line
			(start -0.7874 -0.4064)
			(end -0.7874 0.4064)
			(stroke
				(width 0.1524)
				(type default)
			)
			(layer "B.SilkS")
		)
		(fp_line
			(start 0.67945 0.3048)
			(end 0.67945 -0.305054)
			(stroke
				(width 0.1)
				(type default)
			)
			(layer "B.Fab")
		)
		(fp_line
			(start 0.67945 -0.305054)
			(end 0.12065 -0.305054)
			(stroke
				(width 0.1)
				(type default)
			)
			(layer "B.Fab")
		)
		(fp_line
			(start 0.12065 0.3048)
			(end 0.67945 0.3048)
			(stroke
				(width 0.1)
				(type default)
			)
			(layer "B.Fab")
		)
		(fp_line
			(start 0.12065 0.2794)
			(end 0.12065 0.3048)
			(stroke
				(width 0.1)
				(type default)
			)
			(layer "B.Fab")
		)
		(fp_line
			(start 0.12065 -0.2794)
			(end -0.12065 -0.2794)
			(stroke
				(width 0.1)
				(type default)
			)
			(layer "B.Fab")
		)
		(fp_line
			(start 0.12065 -0.305054)
			(end 0.12065 -0.2794)
			(stroke
				(width 0.1)
				(type default)
			)
			(layer "B.Fab")
		)
		(fp_line
			(start -0.120396 0.3048)
			(end -0.120396 0.2794)
			(stroke
				(width 0.1)
				(type default)
			)
			(layer "B.Fab")
		)
		(fp_line
			(start -0.120396 0.2794)
			(end 0.12065 0.2794)
			(stroke
				(width 0.1)
				(type default)
			)
			(layer "B.Fab")
		)
		(fp_line
			(start -0.12065 -0.2794)
			(end -0.12065 -0.3048)
			(stroke
				(width 0.1)
				(type default)
			)
			(layer "B.Fab")
		)
		(fp_line
			(start -0.12065 -0.3048)
			(end -0.67945 -0.3048)
			(stroke
				(width 0.1)
				(type default)
			)
			(layer "B.Fab")
		)
		(fp_line
			(start -0.67945 0.3048)
			(end -0.120396 0.3048)
			(stroke
				(width 0.1)
				(type default)
			)
			(layer "B.Fab")
		)
		(fp_line
			(start -0.67945 -0.3048)
			(end -0.67945 0.3048)
			(stroke
				(width 0.1)
				(type default)
			)
			(layer "B.Fab")
		)
		(pad "1" smd circle
			(at 0.40005 0)
			(size 0 0)
			(layers "B.Cu" "B.Mask" "B.Paste")
			(net "P3V3_AUX_USB_HUB")
		)
		(pad "2" smd circle
			(at -0.40005 0)
			(size 0 0)
			(layers "B.Cu" "B.Mask" "B.Paste")
			(net "GND")
		)
	)
	(footprint ""
		(layer "B.Cu")
		(at 111.506 -96.738948)
		(property "Reference" "R4021"
			(at 0 0 0)
			(layer "B.SilkS")
			(hide yes)
			(effects
				(font
					(size 1.27 1.27)
				)
				(justify mirror)
			)
		)
		(property "Value" ""
			(at 0 0 0)
			(layer "B.Fab")
			(effects
				(font
					(size 1.27 1.27)
				)
				(justify mirror)
			)
		)
		(duplicate_pad_numbers_are_jumpers no)
		(fp_line
			(start -0.7874 -0.4064)
			(end -0.7874 0.4064)
			(stroke
				(width 0.1524)
				(type default)
			)
			(layer "B.SilkS")
		)
		(fp_line
			(start -0.7874 0.4064)
			(end 0.7874 0.4064)
			(stroke
				(width 0.1524)
				(type default)
			)
			(layer "B.SilkS")
		)
		(fp_line
			(start 0.7874 -0.4064)
			(end -0.7874 -0.4064)
			(stroke
				(width 0.1524)
				(type default)
			)
			(layer "B.SilkS")
		)
		(fp_line
			(start 0.7874 0.4064)
			(end 0.7874 -0.4064)
			(stroke
				(width 0.1524)
				(type default)
			)
			(layer "B.SilkS")
		)
		(fp_line
			(start -0.67945 -0.3048)
			(end -0.67945 0.3048)
			(stroke
				(width 0.1)
				(type default)
			)
			(layer "B.Fab")
		)
		(fp_line
			(start -0.67945 0.3048)
			(end -0.120396 0.3048)
			(stroke
				(width 0.1)
				(type default)
			)
			(layer "B.Fab")
		)
		(fp_line
			(start -0.12065 -0.3048)
			(end -0.67945 -0.3048)
			(stroke
				(width 0.1)
				(type default)
			)
			(layer "B.Fab")
		)
		(fp_line
			(start -0.12065 -0.2794)
			(end -0.12065 -0.3048)
			(stroke
				(width 0.1)
				(type default)
			)
			(layer "B.Fab")
		)
		(fp_line
			(start -0.120396 0.2794)
			(end 0.12065 0.2794)
			(stroke
				(width 0.1)
				(type default)
			)
			(layer "B.Fab")
		)
		(fp_line
			(start -0.120396 0.3048)
			(end -0.120396 0.2794)
			(stroke
				(width 0.1)
				(type default)
			)
			(layer "B.Fab")
		)
		(fp_line
			(start 0.12065 -0.305054)
			(end 0.12065 -0.2794)
			(stroke
				(width 0.1)
				(type default)
			)
			(layer "B.Fab")
		)
		(fp_line
			(start 0.12065 -0.2794)
			(end -0.12065 -0.2794)
			(stroke
				(width 0.1)
				(type default)
			)
			(layer "B.Fab")
		)
		(fp_line
			(start 0.12065 0.2794)
			(end 0.12065 0.3048)
			(stroke
				(width 0.1)
				(type default)
			)
			(layer "B.Fab")
		)
		(fp_line
			(start 0.12065 0.3048)
			(end 0.67945 0.3048)
			(stroke
				(width 0.1)
				(type default)
			)
			(layer "B.Fab")
		)
		(fp_line
			(start 0.67945 -0.305054)
			(end 0.12065 -0.305054)
			(stroke
				(width 0.1)
				(type default)
			)
			(layer "B.Fab")
		)
		(fp_line
			(start 0.67945 0.3048)
			(end 0.67945 -0.305054)
			(stroke
				(width 0.1)
				(type default)
			)
			(layer "B.Fab")
		)
		(pad "1" smd circle
			(at 0.40005 0 180)
			(size 0 0)
			(layers "B.Cu" "B.Mask" "B.Paste")
			(net "PWRGD_CPUPWRGD_LVC2_R")
		)
		(pad "2" smd circle
			(at -0.40005 0 180)
			(size 0 0)
			(layers "B.Cu" "B.Mask" "B.Paste")
			(net "PWRGD_CPUPWRGD_LVC2_R1")
		)
	)
	(footprint ""
		(layer "B.Cu")
		(at 501.065038 -342.799924)
		(property "Reference" "DB5"
			(at 2.584704 -5.768848 270)
			(unlocked yes)
			(layer "B.SilkS")
			(effects
				(font
					(size 0.7874 0.5842)
					(thickness 0.1524)
				)
				(justify left mirror)
			)
		)
		(property "Value" ""
			(at 0 0 0)
			(layer "B.Fab")
			(effects
				(font
					(size 1.27 1.27)
				)
				(justify mirror)
			)
		)
		(duplicate_pad_numbers_are_jumpers no)
		(fp_line
			(start -3.330702 -4.771136)
			(end 0 4.011168)
			(stroke
				(width 0.1524)
				(type default)
			)
			(layer "B.SilkS")
		)
		(fp_line
			(start 0 4.011168)
			(end 2.826766 -3.442462)
			(stroke
				(width 0.1524)
				(type default)
			)
			(layer "B.SilkS")
		)
		(fp_line
			(start 3.18389 -4.383786)
			(end 3.330702 -4.771136)
			(stroke
				(width 0.1524)
				(type default)
			)
			(layer "B.SilkS")
		)
		(fp_line
			(start 3.330702 -4.771136)
			(end -3.330702 -4.771136)
			(stroke
				(width 0.1524)
				(type default)
			)
			(layer "B.SilkS")
		)
		(fp_line
			(start -3.330702 -4.771136)
			(end 0 4.011168)
			(stroke
				(width 0.1)
				(type default)
			)
			(layer "B.Fab")
		)
		(fp_line
			(start 0 4.011168)
			(end 3.330702 -4.771136)
			(stroke
				(width 0.1)
				(type default)
			)
			(layer "B.Fab")
		)
		(fp_line
			(start 3.330702 -4.771136)
			(end -3.330702 -4.771136)
			(stroke
				(width 0.1)
				(type default)
			)
			(layer "B.Fab")
		)
		(pad "1" thru_hole circle
			(at 0 0 180)
			(size 2.159 2.159)
			(drill 1.7018)
			(layers "*.Cu" "*.Mask")
			(remove_unused_layers no)
			(net "T1_GND")
			(clearance 0.0254)
			(thermal_gap 0.0254)
		)
		(pad "2" thru_hole circle
			(at 1.27 -3.348736 180)
			(size 2.159 2.159)
			(drill 1.7018)
			(layers "*.Cu" "*.Mask")
			(remove_unused_layers no)
			(net "TDR_SE_40_OHM_IN4")
			(clearance 0.0254)
			(thermal_gap 0.0254)
		)
		(pad "3" thru_hole circle
			(at -1.27 -3.348736 180)
			(size 2.159 2.159)
			(drill 1.7018)
			(layers "*.Cu" "*.Mask")
			(remove_unused_layers no)
			(net "TDR_SE_40_OHM_IN4")
			(clearance 0.0254)
			(thermal_gap 0.0254)
		)
	)
	(footprint ""
		(layer "B.Cu")
		(at 186.345068 -13.60043 -90)
		(property "Reference" "R597"
			(at 0 0 90)
			(layer "B.SilkS")
			(hide yes)
			(effects
				(font
					(size 1.27 1.27)
				)
				(justify mirror)
			)
		)
		(property "Value" ""
			(at 0 0 90)
			(layer "B.Fab")
			(effects
				(font
					(size 1.27 1.27)
				)
				(justify mirror)
			)
		)
		(duplicate_pad_numbers_are_jumpers no)
		(fp_line
			(start -0.7874 0.4064)
			(end 0.7874 0.4064)
			(stroke
				(width 0.1524)
				(type default)
			)
			(layer "B.SilkS")
		)
		(fp_line
			(start 0.7874 0.4064)
			(end 0.7874 -0.4064)
			(stroke
				(width 0.1524)
				(type default)
			)
			(layer "B.SilkS")
		)
		(fp_line
			(start -0.7874 -0.4064)
			(end -0.7874 0.4064)
			(stroke
				(width 0.1524)
				(type default)
			)
			(layer "B.SilkS")
		)
		(fp_line
			(start 0.7874 -0.4064)
			(end -0.7874 -0.4064)
			(stroke
				(width 0.1524)
				(type default)
			)
			(layer "B.SilkS")
		)
		(fp_line
			(start -0.67945 0.3048)
			(end -0.120396 0.3048)
			(stroke
				(width 0.1)
				(type default)
			)
			(layer "B.Fab")
		)
		(fp_line
			(start -0.120396 0.3048)
			(end -0.120396 0.2794)
			(stroke
				(width 0.1)
				(type default)
			)
			(layer "B.Fab")
		)
		(fp_line
			(start 0.12065 0.3048)
			(end 0.67945 0.3048)
			(stroke
				(width 0.1)
				(type default)
			)
			(layer "B.Fab")
		)
		(fp_line
			(start 0.67945 0.3048)
			(end 0.67945 -0.305054)
			(stroke
				(width 0.1)
				(type default)
			)
			(layer "B.Fab")
		)
		(fp_line
			(start -0.120396 0.2794)
			(end 0.12065 0.2794)
			(stroke
				(width 0.1)
				(type default)
			)
			(layer "B.Fab")
		)
		(fp_line
			(start 0.12065 0.2794)
			(end 0.12065 0.3048)
			(stroke
				(width 0.1)
				(type default)
			)
			(layer "B.Fab")
		)
		(fp_line
			(start -0.12065 -0.2794)
			(end -0.12065 -0.3048)
			(stroke
				(width 0.1)
				(type default)
			)
			(layer "B.Fab")
		)
		(fp_line
			(start 0.12065 -0.2794)
			(end -0.12065 -0.2794)
			(stroke
				(width 0.1)
				(type default)
			)
			(layer "B.Fab")
		)
		(fp_line
			(start -0.67945 -0.3048)
			(end -0.67945 0.3048)
			(stroke
				(width 0.1)
				(type default)
			)
			(layer "B.Fab")
		)
		(fp_line
			(start -0.12065 -0.3048)
			(end -0.67945 -0.3048)
			(stroke
				(width 0.1)
				(type default)
			)
			(layer "B.Fab")
		)
		(fp_line
			(start 0.12065 -0.305054)
			(end 0.12065 -0.2794)
			(stroke
				(width 0.1)
				(type default)
			)
			(layer "B.Fab")
		)
		(fp_line
			(start 0.67945 -0.305054)
			(end 0.12065 -0.305054)
			(stroke
				(width 0.1)
				(type default)
			)
			(layer "B.Fab")
		)
		(pad "1" smd circle
			(at 0.40005 0 90)
			(size 0 0)
			(layers "B.Cu" "B.Mask" "B.Paste")
			(net "I3C_SPD_DDRABCD_CPU1_BMC_R_SCL")
		)
		(pad "2" smd circle
			(at -0.40005 0 90)
			(size 0 0)
			(layers "B.Cu" "B.Mask" "B.Paste")
			(net "I3C_SPD_DDRABCD_CPU1_BMC_SCL")
		)
	)
	(footprint ""
		(layer "B.Cu")
		(at 110.866936 -359.47985)
		(property "Reference" "PR305"
			(at 0 0 0)
			(layer "B.SilkS")
			(hide yes)
			(effects
				(font
					(size 1.27 1.27)
				)
				(justify mirror)
			)
		)
		(property "Value" ""
			(at 0 0 0)
			(layer "B.Fab")
			(effects
				(font
					(size 1.27 1.27)
				)
				(justify mirror)
			)
		)
		(duplicate_pad_numbers_are_jumpers no)
		(fp_line
			(start -0.7874 -0.4064)
			(end -0.7874 0.4064)
			(stroke
				(width 0.1524)
				(type default)
			)
			(layer "B.SilkS")
		)
		(fp_line
			(start -0.7874 0.4064)
			(end 0.7874 0.4064)
			(stroke
				(width 0.1524)
				(type default)
			)
			(layer "B.SilkS")
		)
		(fp_line
			(start 0.7874 -0.4064)
			(end -0.7874 -0.4064)
			(stroke
				(width 0.1524)
				(type default)
			)
			(layer "B.SilkS")
		)
		(fp_line
			(start 0.7874 0.4064)
			(end 0.7874 -0.4064)
			(stroke
				(width 0.1524)
				(type default)
			)
			(layer "B.SilkS")
		)
		(fp_line
			(start -0.67945 -0.3048)
			(end -0.67945 0.3048)
			(stroke
				(width 0.1)
				(type default)
			)
			(layer "B.Fab")
		)
		(fp_line
			(start -0.67945 0.3048)
			(end -0.120396 0.3048)
			(stroke
				(width 0.1)
				(type default)
			)
			(layer "B.Fab")
		)
		(fp_line
			(start -0.12065 -0.3048)
			(end -0.67945 -0.3048)
			(stroke
				(width 0.1)
				(type default)
			)
			(layer "B.Fab")
		)
		(fp_line
			(start -0.12065 -0.2794)
			(end -0.12065 -0.3048)
			(stroke
				(width 0.1)
				(type default)
			)
			(layer "B.Fab")
		)
		(fp_line
			(start -0.120396 0.2794)
			(end 0.12065 0.2794)
			(stroke
				(width 0.1)
				(type default)
			)
			(layer "B.Fab")
		)
		(fp_line
			(start -0.120396 0.3048)
			(end -0.120396 0.2794)
			(stroke
				(width 0.1)
				(type default)
			)
			(layer "B.Fab")
		)
		(fp_line
			(start 0.12065 -0.305054)
			(end 0.12065 -0.2794)
			(stroke
				(width 0.1)
				(type default)
			)
			(layer "B.Fab")
		)
		(fp_line
			(start 0.12065 -0.2794)
			(end -0.12065 -0.2794)
			(stroke
				(width 0.1)
				(type default)
			)
			(layer "B.Fab")
		)
		(fp_line
			(start 0.12065 0.2794)
			(end 0.12065 0.3048)
			(stroke
				(width 0.1)
				(type default)
			)
			(layer "B.Fab")
		)
		(fp_line
			(start 0.12065 0.3048)
			(end 0.67945 0.3048)
			(stroke
				(width 0.1)
				(type default)
			)
			(layer "B.Fab")
		)
		(fp_line
			(start 0.67945 -0.305054)
			(end 0.12065 -0.305054)
			(stroke
				(width 0.1)
				(type default)
			)
			(layer "B.Fab")
		)
		(fp_line
			(start 0.67945 0.3048)
			(end 0.67945 -0.305054)
			(stroke
				(width 0.1)
				(type default)
			)
			(layer "B.Fab")
		)
		(pad "1" smd circle
			(at 0.40005 0 180)
			(size 0 0)
			(layers "B.Cu" "B.Mask" "B.Paste")
			(net "PVCCIN_CPU1_CSPIN")
		)
		(pad "2" smd circle
			(at -0.40005 0 180)
			(size 0 0)
			(layers "B.Cu" "B.Mask" "B.Paste")
			(net "GND")
		)
	)
)
